(kicad_pcb
	(version 20260206)
	(generator "pcbnew")
	(generator_version "10.0")
	(general
		(thickness 1.6)
		(legacy_teardrops no)
	)
	(paper "A4")
	(title_block
		(title "pdpb — Lightning_PDPB_BRD.brd")
		(comment 1 "Lightning (Wiwynn / Facebook NVMe JBOF) / footprints 373-377 of 1140")
	)
	(layers
		(0 "F.Cu" signal "TOP")
		(4 "In1.Cu" signal "L2GND")
		(6 "In2.Cu" signal "L3")
		(8 "In3.Cu" signal "L4VCC")
		(10 "In4.Cu" signal "L5VCC")
		(12 "In5.Cu" signal "L6")
		(14 "In6.Cu" signal "L7GND")
		(2 "B.Cu" signal "BOTTOM")
		(9 "F.Adhes" user "F.Adhesive")
		(11 "B.Adhes" user "B.Adhesive")
		(13 "F.Paste" user "Package Geometry/Pastemask Top")
		(15 "B.Paste" user "Package Geometry/Pastemask Bottom")
		(5 "F.SilkS" user "Ref Des/Silkscreen Top")
		(7 "B.SilkS" user "Ref Des/Silkscreen Bottom")
		(1 "F.Mask" user "Board Geometry/Soldermask Top")
		(3 "B.Mask" user "Board Geometry/Soldermask Bottom")
		(17 "Dwgs.User" user "User.Drawings")
		(19 "Cmts.User" user "User.Comments")
		(21 "Eco1.User" user "User.Eco1")
		(23 "Eco2.User" user "User.Eco2")
		(25 "Edge.Cuts" user "Board Geometry/Outline")
		(27 "Margin" user)
		(31 "F.CrtYd" user "Package Geometry/Place Bound Top")
		(29 "B.CrtYd" user "Package Geometry/Place Bound Bottom")
		(35 "F.Fab" user "Ref Des/Assembly Top")
		(33 "B.Fab" user "Ref Des/Assembly Bottom")
	)
	(footprint ""
		(layer "F.Cu")
		(at 30.6578 -493.7506 90)
		(property "Reference" "SR1101"
			(at 0 0 90)
			(layer "F.SilkS")
			(hide yes)
			(effects
				(font
					(size 1.27 1.27)
				)
			)
		)
		(property "Value" "4K7R2F-GP"
			(at 0.064008 -3.993896 90)
			(unlocked yes)
			(layer "F.Fab")
			(hide yes)
			(effects
				(font
					(size 1.016 1.016)
					(thickness 0.1524)
				)
			)
		)
		(property "Device Type" "R402H16"
			(at 0.064008 -5.517896 90)
			(unlocked yes)
			(layer "F.Fab")
			(hide yes)
			(effects
				(font
					(size 1.016 1.016)
					(thickness 0.1524)
				)
			)
		)
		(duplicate_pad_numbers_are_jumpers no)
		(fp_line
			(start 0.508 -0.9398)
			(end -0.508 -0.9398)
			(stroke
				(width 0.1524)
				(type default)
			)
			(layer "F.SilkS")
		)
		(fp_line
			(start -0.508 -0.9398)
			(end -0.508 0.9398)
			(stroke
				(width 0.1524)
				(type default)
			)
			(layer "F.SilkS")
		)
		(fp_rect
			(start -0.508 0.9398)
			(end 0.508 -0.9398)
			(stroke
				(width 0)
				(type default)
			)
			(fill no)
			(layer "F.CrtYd")
		)
		(fp_rect
			(start -0.508 0.9398)
			(end 0.508 -0.9398)
			(stroke
				(width 0)
				(type default)
			)
			(fill no)
			(layer "F.Fab")
		)
		(pad "1" smd custom
			(at 0 -0.4445 90)
			(size 0.1397 0.1397)
			(layers "F.Cu" "F.Mask" "F.Paste")
			(net "P3V3")
			(options
				(clearance outline)
				(anchor circle)
			)
			(primitives
				(gr_poly
					(pts
						(arc
							(start -0.1778 -0.2794)
							(mid -0.249642 -0.249642)
							(end -0.2794 -0.1778)
						)
						(arc
							(start -0.2794 0.1778)
							(mid -0.249642 0.249642)
							(end -0.1778 0.2794)
						)
						(arc
							(start 0.1778 0.2794)
							(mid 0.249642 0.249642)
							(end 0.2794 0.1778)
						)
						(arc
							(start 0.2794 -0.1778)
							(mid 0.249642 -0.249642)
							(end 0.1778 -0.2794)
						)
					)
					(width 0)
					(fill yes)
				)
			)
		)
		(pad "2" smd custom
			(at 0 0.4445 90)
			(size 0.1397 0.1397)
			(layers "F.Cu" "F.Mask" "F.Paste")
			(net "DUALPORTEN#5")
			(options
				(clearance outline)
				(anchor circle)
			)
			(primitives
				(gr_poly
					(pts
						(arc
							(start -0.1778 -0.2794)
							(mid -0.249642 -0.249642)
							(end -0.2794 -0.1778)
						)
						(arc
							(start -0.2794 0.1778)
							(mid -0.249642 0.249642)
							(end -0.1778 0.2794)
						)
						(arc
							(start 0.1778 0.2794)
							(mid 0.249642 0.249642)
							(end 0.2794 0.1778)
						)
						(arc
							(start 0.2794 -0.1778)
							(mid 0.249642 -0.249642)
							(end 0.1778 -0.2794)
						)
					)
					(width 0)
					(fill yes)
				)
			)
		)
	)
	(footprint ""
		(layer "F.Cu")
		(at 51.903884 -450.088 -90)
		(property "Reference" "U202"
			(at 0 0 270)
			(layer "F.SilkS")
			(hide yes)
			(effects
				(font
					(size 1.27 1.27)
				)
			)
		)
		(property "Value" "SN74LVC1G08DCKR-GP"
			(at -2.3368 -8.6868 270)
			(unlocked yes)
			(layer "F.Fab")
			(hide yes)
			(effects
				(font
					(size 1.016 1.016)
					(thickness 0.1524)
				)
			)
		)
		(property "Device Type" "SC70-5H44"
			(at -2.3114 -10.414 270)
			(unlocked yes)
			(layer "F.Fab")
			(hide yes)
			(effects
				(font
					(size 1.016 1.016)
					(thickness 0.1524)
				)
			)
		)
		(duplicate_pad_numbers_are_jumpers no)
		(fp_line
			(start -1.27 1.7018)
			(end -1.27 -1.7018)
			(stroke
				(width 0.1524)
				(type default)
			)
			(layer "F.SilkS")
		)
		(fp_line
			(start 1.27 1.7018)
			(end -1.27 1.7018)
			(stroke
				(width 0.1524)
				(type default)
			)
			(layer "F.SilkS")
		)
		(fp_line
			(start -1.27 -1.7018)
			(end 1.27 -1.7018)
			(stroke
				(width 0.1524)
				(type default)
			)
			(layer "F.SilkS")
		)
		(fp_line
			(start 1.27 -1.7018)
			(end 1.27 1.7018)
			(stroke
				(width 0.1524)
				(type default)
			)
			(layer "F.SilkS")
		)
		(fp_line
			(start 0.6604 -1.8034)
			(end 1.3843 -1.8034)
			(stroke
				(width 0.3302)
				(type default)
			)
			(layer "F.SilkS")
		)
		(fp_line
			(start 1.3843 -1.8034)
			(end 1.3843 -1.1176)
			(stroke
				(width 0.3302)
				(type default)
			)
			(layer "F.SilkS")
		)
		(fp_rect
			(start -1.524 1.9558)
			(end 1.524 -1.9558)
			(stroke
				(width 0)
				(type default)
			)
			(fill no)
			(layer "F.CrtYd")
		)
		(fp_poly
			(pts
				(xy -1.524 -1.9558) (xy 1.524 -1.9558) (xy 1.524 1.9558) (xy -1.524 1.9558)
			)
			(stroke
				(width 0)
				(type default)
			)
			(fill no)
			(layer "F.Fab")
		)
		(pad "1" smd rect
			(at 0.65024 -0.8255 270)
			(size 0.4064 1.2192)
			(layers "F.Cu" "F.Mask" "F.Paste")
			(net "SSD5_CLK0_OE_MOS_N")
		)
		(pad "2" smd rect
			(at 0 -0.8255 270)
			(size 0.4064 1.2192)
			(layers "F.Cu" "F.Mask" "F.Paste")
			(net "ATTN_LED_DR5_N")
		)
		(pad "3" smd rect
			(at -0.65024 -0.8255 270)
			(size 0.4064 1.2192)
			(layers "F.Cu" "F.Mask" "F.Paste")
			(net "GND")
		)
		(pad "4" smd rect
			(at -0.65024 0.8255 270)
			(size 0.4064 1.2192)
			(layers "F.Cu" "F.Mask" "F.Paste")
			(net "ATTN_LED_DR5_AND")
		)
		(pad "5" smd rect
			(at 0.65024 0.8255 270)
			(size 0.4064 1.2192)
			(layers "F.Cu" "F.Mask" "F.Paste")
			(net "P3V3")
		)
	)
	(footprint ""
		(layer "F.Cu")
		(at 205.867 -456.438)
		(property "Reference" "TP4"
			(at 0 0 0)
			(layer "F.SilkS")
			(hide yes)
			(effects
				(font
					(size 1.27 1.27)
				)
			)
		)
		(property "Value" "TPAD32-GP"
			(at -0.0508 -1.6764 0)
			(unlocked yes)
			(layer "F.Fab")
			(hide yes)
			(effects
				(font
					(size 1.016 1.016)
					(thickness 0.1524)
				)
			)
		)
		(property "Device Type" "TPAD32"
			(at -0.0508 -3.2004 0)
			(unlocked yes)
			(layer "F.Fab")
			(hide yes)
			(effects
				(font
					(size 1.016 1.016)
					(thickness 0.1524)
				)
			)
		)
		(duplicate_pad_numbers_are_jumpers no)
		(fp_poly
			(pts
				(arc
					(start 0.4064 0)
					(mid -0.4064 0)
					(end 0.4064 0)
				)
			)
			(stroke
				(width 0)
				(type default)
			)
			(fill no)
			(layer "F.CrtYd")
		)
		(fp_poly
			(pts
				(arc
					(start 0.7112 0)
					(mid -0.7112 0)
					(end 0.7112 0)
				)
			)
			(stroke
				(width 0)
				(type default)
			)
			(fill no)
			(layer "F.Fab")
		)
		(pad "1" smd circle
			(at 0 0)
			(size 0.8128 0.8128)
			(layers "F.Cu" "F.Mask" "F.Paste")
			(net "I2C_B_TMP2_ALERT")
		)
	)
	(footprint ""
		(layer "F.Cu")
		(at 94.869 -202.184)
		(property "Reference" "R9088"
			(at 0 0 0)
			(layer "F.SilkS")
			(hide yes)
			(effects
				(font
					(size 1.27 1.27)
				)
			)
		)
		(property "Value" "27R2F-GP"
			(at 0.064008 -3.993896 0)
			(unlocked yes)
			(layer "F.Fab")
			(hide yes)
			(effects
				(font
					(size 1.016 1.016)
					(thickness 0.1524)
				)
			)
		)
		(property "Device Type" "R402H16"
			(at 0.064008 -5.517896 0)
			(unlocked yes)
			(layer "F.Fab")
			(hide yes)
			(effects
				(font
					(size 1.016 1.016)
					(thickness 0.1524)
				)
			)
		)
		(duplicate_pad_numbers_are_jumpers no)
		(fp_line
			(start -0.508 -0.9398)
			(end -0.508 0.9398)
			(stroke
				(width 0.1524)
				(type default)
			)
			(layer "F.SilkS")
		)
		(fp_line
			(start 0.508 -0.9398)
			(end -0.508 -0.9398)
			(stroke
				(width 0.1524)
				(type default)
			)
			(layer "F.SilkS")
		)
		(fp_rect
			(start -0.508 0.9398)
			(end 0.508 -0.9398)
			(stroke
				(width 0)
				(type default)
			)
			(fill no)
			(layer "F.CrtYd")
		)
		(fp_rect
			(start -0.508 0.9398)
			(end 0.508 -0.9398)
			(stroke
				(width 0)
				(type default)
			)
			(fill no)
			(layer "F.Fab")
		)
		(pad "1" smd custom
			(at 0 -0.4445)
			(size 0.1397 0.1397)
			(layers "F.Cu" "F.Mask" "F.Paste")
			(net "PE_CLK_100M_DR4_2_R_N")
			(options
				(clearance outline)
				(anchor circle)
			)
			(primitives
				(gr_poly
					(pts
						(arc
							(start -0.1778 -0.2794)
							(mid -0.249642 -0.249642)
							(end -0.2794 -0.1778)
						)
						(arc
							(start -0.2794 0.1778)
							(mid -0.249642 0.249642)
							(end -0.1778 0.2794)
						)
						(arc
							(start 0.1778 0.2794)
							(mid 0.249642 0.249642)
							(end 0.2794 0.1778)
						)
						(arc
							(start 0.2794 -0.1778)
							(mid 0.249642 -0.249642)
							(end 0.1778 -0.2794)
						)
					)
					(width 0)
					(fill yes)
				)
			)
		)
		(pad "2" smd custom
			(at 0 0.4445)
			(size 0.1397 0.1397)
			(layers "F.Cu" "F.Mask" "F.Paste")
			(net "PE_CLK100M_DR4_2_N")
			(options
				(clearance outline)
				(anchor circle)
			)
			(primitives
				(gr_poly
					(pts
						(arc
							(start -0.1778 -0.2794)
							(mid -0.249642 -0.249642)
							(end -0.2794 -0.1778)
						)
						(arc
							(start -0.2794 0.1778)
							(mid -0.249642 0.249642)
							(end -0.1778 0.2794)
						)
						(arc
							(start 0.1778 0.2794)
							(mid 0.249642 0.249642)
							(end 0.2794 0.1778)
						)
						(arc
							(start 0.2794 -0.1778)
							(mid 0.249642 -0.249642)
							(end 0.1778 -0.2794)
						)
					)
					(width 0)
					(fill yes)
				)
			)
		)
	)
	(footprint ""
		(layer "F.Cu")
		(at 29.6418 -396.6464 -90)
		(property "Reference" "U15"
			(at 0 0 270)
			(layer "F.SilkS")
			(hide yes)
			(effects
				(font
					(size 1.27 1.27)
				)
			)
		)
		(property "Value" "P2003EVG-GP"
			(at 0 -11.1252 270)
			(unlocked yes)
			(layer "F.Fab")
			(hide yes)
			(effects
				(font
					(size 1.016 1.016)
					(thickness 0.1524)
				)
			)
		)
		(property "Device Type" "SOIC8H79"
			(at 0 -12.6492 270)
			(unlocked yes)
			(layer "F.Fab")
			(hide yes)
			(effects
				(font
					(size 1.016 1.016)
					(thickness 0.1524)
				)
			)
		)
		(duplicate_pad_numbers_are_jumpers no)
		(fp_line
			(start -2.6162 3.429)
			(end -2.6162 1.4732)
			(stroke
				(width 0.4064)
				(type default)
			)
			(layer "F.SilkS")
		)
		(fp_line
			(start -2.7432 1.4224)
			(end 2.1336 1.4224)
			(stroke
				(width 0.1524)
				(type default)
			)
			(layer "F.SilkS")
		)
		(fp_line
			(start 2.1336 1.4224)
			(end 2.1336 -1.4224)
			(stroke
				(width 0.1524)
				(type default)
			)
			(layer "F.SilkS")
		)
		(fp_line
			(start -2.2352 0)
			(end -2.7432 0.508)
			(stroke
				(width 0.1524)
				(type default)
			)
			(layer "F.SilkS")
		)
		(fp_line
			(start -2.7432 -0.508)
			(end -2.2352 0)
			(stroke
				(width 0.1524)
				(type default)
			)
			(layer "F.SilkS")
		)
		(fp_line
			(start -2.7432 -1.4224)
			(end -2.7432 1.4224)
			(stroke
				(width 0.1524)
				(type default)
			)
			(layer "F.SilkS")
		)
		(fp_line
			(start 2.1336 -1.4224)
			(end -2.7432 -1.4224)
			(stroke
				(width 0.1524)
				(type default)
			)
			(layer "F.SilkS")
		)
		(fp_poly
			(pts
				(xy 2.2098 -1.4224) (xy 2.2098 1.4224) (xy -2.2225 1.4224) (xy -2.2225 -1.4224)
			)
			(stroke
				(width 0)
				(type default)
			)
			(fill yes)
			(layer "F.SilkS")
		)
		(fp_rect
			(start -2.4511 2.9972)
			(end 2.4511 -2.9972)
			(stroke
				(width 0)
				(type default)
			)
			(fill no)
			(layer "F.CrtYd")
		)
		(fp_poly
			(pts
				(xy -2.8194 3.6322) (xy -2.8194 -3.6322) (xy 2.8194 -3.6322) (xy 2.8194 -2.2987) (xy 2.4511 -2.2987)
				(xy 2.4511 -2.9972) (xy -2.4511 -2.9972) (xy -2.4511 2.9972) (xy 2.4511 2.9972) (xy 2.4511 -2.286)
				(xy 2.8194 -2.286) (xy 2.8194 3.6322)
			)
			(stroke
				(width 0)
				(type default)
			)
			(fill no)
			(layer "F.CrtYd")
		)
		(fp_rect
			(start -2.8194 3.6322)
			(end 2.8194 -3.6322)
			(stroke
				(width 0)
				(type default)
			)
			(fill no)
			(layer "F.Fab")
		)
		(pad "1" smd rect
			(at -1.905 2.54 270)
			(size 0.635 1.651)
			(layers "F.Cu" "F.Mask" "F.Paste")
			(net "P12V")
		)
		(pad "2" smd rect
			(at -0.635 2.54 270)
			(size 0.635 1.651)
			(layers "F.Cu" "F.Mask" "F.Paste")
			(net "P12V")
		)
		(pad "3" smd rect
			(at 0.635 2.54 270)
			(size 0.635 1.651)
			(layers "F.Cu" "F.Mask" "F.Paste")
			(net "P12V")
		)
		(pad "4" smd rect
			(at 1.905 2.54 270)
			(size 0.635 1.651)
			(layers "F.Cu" "F.Mask" "F.Paste")
			(net "SW_SSD6_N")
		)
		(pad "5" smd rect
			(at 1.905 -2.54 270)
			(size 0.635 1.651)
			(layers "F.Cu" "F.Mask" "F.Paste")
			(net "P12V_SSD6")
		)
		(pad "6" smd rect
			(at 0.635 -2.54 270)
			(size 0.635 1.651)
			(layers "F.Cu" "F.Mask" "F.Paste")
			(net "P12V_SSD6")
		)
		(pad "7" smd rect
			(at -0.635 -2.54 270)
			(size 0.635 1.651)
			(layers "F.Cu" "F.Mask" "F.Paste")
			(net "P12V_SSD6")
		)
		(pad "8" smd rect
			(at -1.905 -2.54 270)
			(size 0.635 1.651)
			(layers "F.Cu" "F.Mask" "F.Paste")
			(net "P12V_SSD6")
		)
	)
)
